(kicad_pcb
	(version 20260206)
	(generator "pcbnew")
	(generator_version "10.0")
	(general
		(thickness 1.6)
		(legacy_teardrops no)
	)
	(paper "A4")
	(title_block
		(title "03242023_DA0F0TMBIJ0_F0T_Motherboard_J_brd_V01_OCP.brd")
		(comment 1 "Grand Teton / footprint 3198 of 6105 (J12), pads 225-291 of 291")
	)
	(layers
		(0 "F.Cu" signal "TOP")
		(4 "In1.Cu" signal "GND")
		(6 "In2.Cu" signal "IN1")
		(8 "In3.Cu" signal "GND1")
		(10 "In4.Cu" signal "IN2")
		(12 "In5.Cu" signal "GND2")
		(14 "In6.Cu" signal "IN3")
		(16 "In7.Cu" signal "GND3")
		(18 "In8.Cu" signal "VCC")
		(20 "In9.Cu" signal "VCC1")
		(22 "In10.Cu" signal "GND4")
		(24 "In11.Cu" signal "IN4")
		(26 "In12.Cu" signal "GND5")
		(28 "In13.Cu" signal "IN5")
		(30 "In14.Cu" signal "GND6")
		(32 "In15.Cu" signal "IN6")
		(34 "In16.Cu" signal "GND7")
		(2 "B.Cu" signal "BOTTOM")
		(9 "F.Adhes" user "F.Adhesive")
		(11 "B.Adhes" user "B.Adhesive")
		(13 "F.Paste" user "Package Geometry/Pastemask Top")
		(15 "B.Paste" user "Package Geometry/Pastemask Bottom")
		(5 "F.SilkS" user "Ref Des/Silkscreen Top")
		(7 "B.SilkS" user "Ref Des/Silkscreen Bottom")
		(1 "F.Mask" user "Board Geometry/Soldermask Top")
		(3 "B.Mask" user "Board Geometry/Soldermask Bottom")
		(17 "Dwgs.User" user "User.Drawings")
		(19 "Cmts.User" user "User.Comments")
		(21 "Eco1.User" user "User.Eco1")
		(23 "Eco2.User" user "User.Eco2")
		(25 "Edge.Cuts" user "Board Geometry/Outline")
		(27 "Margin" user)
		(31 "F.CrtYd" user "Package Geometry/Place Bound Top")
		(29 "B.CrtYd" user "Package Geometry/Place Bound Bottom")
		(35 "F.Fab" user "Ref Des/Assembly Top")
		(33 "B.Fab" user "Ref Des/Assembly Bottom")
	)
	(footprint ""
		(layer "F.Cu")
		(at 423.890948 -258.091686)
		(property "Reference" "J12"
			(at -3.683 -81.702148 0)
			(unlocked yes)
			(layer "F.SilkS")
			(effects
				(font
					(size 0.7874 0.5842)
					(thickness 0.1524)
				)
				(justify left)
			)
		)
		(property "Value" ""
			(at 0 0 0)
			(layer "F.Fab")
			(effects
				(font
					(size 1.27 1.27)
				)
			)
		)
		(duplicate_pad_numbers_are_jumpers no)
		(pad "225" smd rect
			(at 2.050034 9.774936 270)
			(size 0.519938 1.4986)
			(layers "F.Cu" "F.Mask" "F.Paste")
			(net "M_F_CPU0_SB_CA<5>")
		)
		(pad "226" smd rect
			(at 2.050034 10.625074 270)
			(size 0.519938 1.4986)
			(layers "F.Cu" "F.Mask" "F.Paste")
			(net "GND")
		)
		(pad "227" smd rect
			(at 2.050034 11.474958 270)
			(size 0.519938 1.4986)
			(layers "F.Cu" "F.Mask" "F.Paste")
			(net "M_F_CPU0_SB_PAR")
		)
		(pad "228" smd rect
			(at 2.050034 12.325096 270)
			(size 0.519938 1.4986)
			(layers "F.Cu" "F.Mask" "F.Paste")
			(net "GND")
		)
		(pad "229" smd rect
			(at 2.050034 13.17498 270)
			(size 0.519938 1.4986)
			(layers "F.Cu" "F.Mask" "F.Paste")
			(net "M_F_CPU0_SB_CS_N<3>")
		)
		(pad "230" smd rect
			(at 2.050034 14.025118 270)
			(size 0.519938 1.4986)
			(layers "F.Cu" "F.Mask" "F.Paste")
			(net "GND")
		)
		(pad "231" smd rect
			(at 2.050034 14.875002 270)
			(size 0.519938 1.4986)
			(layers "F.Cu" "F.Mask" "F.Paste")
			(net "TP_CHF_CPU0_DIMM2_FRU_5")
		)
		(pad "232" smd rect
			(at 2.050034 15.724886 270)
			(size 0.519938 1.4986)
			(layers "F.Cu" "F.Mask" "F.Paste")
			(net "TP_CHF_CPU0_DIMM2_FRU_6")
		)
		(pad "233" smd rect
			(at 2.050034 16.575024 270)
			(size 0.519938 1.4986)
			(layers "F.Cu" "F.Mask" "F.Paste")
			(net "GND")
		)
		(pad "234" smd rect
			(at 2.050034 17.424908 270)
			(size 0.519938 1.4986)
			(layers "F.Cu" "F.Mask" "F.Paste")
			(net "M_F_CPU0_SB_CB<6>")
		)
		(pad "235" smd rect
			(at 2.050034 18.275046 270)
			(size 0.519938 1.4986)
			(layers "F.Cu" "F.Mask" "F.Paste")
			(net "GND")
		)
		(pad "236" smd rect
			(at 2.050034 19.12493 270)
			(size 0.519938 1.4986)
			(layers "F.Cu" "F.Mask" "F.Paste")
			(net "M_F_CPU0_SB_CB<7>")
		)
		(pad "237" smd rect
			(at 2.050034 19.975068 270)
			(size 0.519938 1.4986)
			(layers "F.Cu" "F.Mask" "F.Paste")
			(net "GND")
		)
		(pad "238" smd rect
			(at 2.050034 20.824952 270)
			(size 0.519938 1.4986)
			(layers "F.Cu" "F.Mask" "F.Paste")
			(net "M_F_CPU0_SB_DQS_DN<4>")
		)
		(pad "239" smd rect
			(at 2.050034 21.67509 270)
			(size 0.519938 1.4986)
			(layers "F.Cu" "F.Mask" "F.Paste")
			(net "M_F_CPU0_SB_DQS_DP<4>")
		)
		(pad "240" smd rect
			(at 2.050034 22.524974 270)
			(size 0.519938 1.4986)
			(layers "F.Cu" "F.Mask" "F.Paste")
			(net "GND")
		)
		(pad "241" smd rect
			(at 2.050034 23.375112 270)
			(size 0.519938 1.4986)
			(layers "F.Cu" "F.Mask" "F.Paste")
			(net "M_F_CPU0_SB_CB<2>")
		)
		(pad "242" smd rect
			(at 2.050034 24.224996 270)
			(size 0.519938 1.4986)
			(layers "F.Cu" "F.Mask" "F.Paste")
			(net "GND")
		)
		(pad "243" smd rect
			(at 2.050034 25.07488 270)
			(size 0.519938 1.4986)
			(layers "F.Cu" "F.Mask" "F.Paste")
			(net "M_F_CPU0_SB_CB<3>")
		)
		(pad "244" smd rect
			(at 2.050034 25.925018 270)
			(size 0.519938 1.4986)
			(layers "F.Cu" "F.Mask" "F.Paste")
			(net "GND")
		)
		(pad "245" smd rect
			(at 2.050034 26.774902 270)
			(size 0.519938 1.4986)
			(layers "F.Cu" "F.Mask" "F.Paste")
			(net "M_F_CPU0_SB_DQ<2>")
		)
		(pad "246" smd rect
			(at 2.050034 27.62504 270)
			(size 0.519938 1.4986)
			(layers "F.Cu" "F.Mask" "F.Paste")
			(net "GND")
		)
		(pad "247" smd rect
			(at 2.050034 28.474924 270)
			(size 0.519938 1.4986)
			(layers "F.Cu" "F.Mask" "F.Paste")
			(net "M_F_CPU0_SB_DQ<3>")
		)
		(pad "248" smd rect
			(at 2.050034 29.325062 270)
			(size 0.519938 1.4986)
			(layers "F.Cu" "F.Mask" "F.Paste")
			(net "GND")
		)
		(pad "249" smd rect
			(at 2.050034 30.174946 270)
			(size 0.519938 1.4986)
			(layers "F.Cu" "F.Mask" "F.Paste")
			(net "M_F_CPU0_SB_DQS_DN<5>")
		)
		(pad "250" smd rect
			(at 2.050034 31.025084 270)
			(size 0.519938 1.4986)
			(layers "F.Cu" "F.Mask" "F.Paste")
			(net "M_F_CPU0_SB_DQS_DP<5>")
		)
		(pad "251" smd rect
			(at 2.050034 31.874968 270)
			(size 0.519938 1.4986)
			(layers "F.Cu" "F.Mask" "F.Paste")
			(net "GND")
		)
		(pad "252" smd rect
			(at 2.050034 32.725106 270)
			(size 0.519938 1.4986)
			(layers "F.Cu" "F.Mask" "F.Paste")
			(net "M_F_CPU0_SB_DQ<6>")
		)
		(pad "253" smd rect
			(at 2.050034 33.57499 270)
			(size 0.519938 1.4986)
			(layers "F.Cu" "F.Mask" "F.Paste")
			(net "GND")
		)
		(pad "254" smd rect
			(at 2.050034 34.425128 270)
			(size 0.519938 1.4986)
			(layers "F.Cu" "F.Mask" "F.Paste")
			(net "M_F_CPU0_SB_DQ<7>")
		)
		(pad "255" smd rect
			(at 2.050034 35.275012 270)
			(size 0.519938 1.4986)
			(layers "F.Cu" "F.Mask" "F.Paste")
			(net "GND")
		)
		(pad "256" smd rect
			(at 2.050034 36.124896 270)
			(size 0.519938 1.4986)
			(layers "F.Cu" "F.Mask" "F.Paste")
			(net "M_F_CPU0_SB_DQ<10>")
		)
		(pad "257" smd rect
			(at 2.050034 36.975034 270)
			(size 0.519938 1.4986)
			(layers "F.Cu" "F.Mask" "F.Paste")
			(net "GND")
		)
		(pad "258" smd rect
			(at 2.050034 37.824918 270)
			(size 0.519938 1.4986)
			(layers "F.Cu" "F.Mask" "F.Paste")
			(net "M_F_CPU0_SB_DQ<11>")
		)
		(pad "259" smd rect
			(at 2.050034 38.675056 270)
			(size 0.519938 1.4986)
			(layers "F.Cu" "F.Mask" "F.Paste")
			(net "GND")
		)
		(pad "260" smd rect
			(at 2.050034 39.52494 270)
			(size 0.519938 1.4986)
			(layers "F.Cu" "F.Mask" "F.Paste")
			(net "M_F_CPU0_SB_DQS_DN<6>")
		)
		(pad "261" smd rect
			(at 2.050034 40.375078 270)
			(size 0.519938 1.4986)
			(layers "F.Cu" "F.Mask" "F.Paste")
			(net "M_F_CPU0_SB_DQS_DP<6>")
		)
		(pad "262" smd rect
			(at 2.050034 41.224962 270)
			(size 0.519938 1.4986)
			(layers "F.Cu" "F.Mask" "F.Paste")
			(net "GND")
		)
		(pad "263" smd rect
			(at 2.050034 42.0751 270)
			(size 0.519938 1.4986)
			(layers "F.Cu" "F.Mask" "F.Paste")
			(net "M_F_CPU0_SB_DQ<14>")
		)
		(pad "264" smd rect
			(at 2.050034 42.924984 270)
			(size 0.519938 1.4986)
			(layers "F.Cu" "F.Mask" "F.Paste")
			(net "GND")
		)
		(pad "265" smd rect
			(at 2.050034 43.775122 270)
			(size 0.519938 1.4986)
			(layers "F.Cu" "F.Mask" "F.Paste")
			(net "M_F_CPU0_SB_DQ<15>")
		)
		(pad "266" smd rect
			(at 2.050034 44.625006 270)
			(size 0.519938 1.4986)
			(layers "F.Cu" "F.Mask" "F.Paste")
			(net "GND")
		)
		(pad "267" smd rect
			(at 2.050034 45.47489 270)
			(size 0.519938 1.4986)
			(layers "F.Cu" "F.Mask" "F.Paste")
			(net "M_F_CPU0_SB_DQ<18>")
		)
		(pad "268" smd rect
			(at 2.050034 46.325028 270)
			(size 0.519938 1.4986)
			(layers "F.Cu" "F.Mask" "F.Paste")
			(net "GND")
		)
		(pad "269" smd rect
			(at 2.050034 47.174912 270)
			(size 0.519938 1.4986)
			(layers "F.Cu" "F.Mask" "F.Paste")
			(net "M_F_CPU0_SB_DQ<19>")
		)
		(pad "270" smd rect
			(at 2.050034 48.02505 270)
			(size 0.519938 1.4986)
			(layers "F.Cu" "F.Mask" "F.Paste")
			(net "GND")
		)
		(pad "271" smd rect
			(at 2.050034 48.874934 270)
			(size 0.519938 1.4986)
			(layers "F.Cu" "F.Mask" "F.Paste")
			(net "M_F_CPU0_SB_DQS_DN<7>")
		)
		(pad "272" smd rect
			(at 2.050034 49.725072 270)
			(size 0.519938 1.4986)
			(layers "F.Cu" "F.Mask" "F.Paste")
			(net "M_F_CPU0_SB_DQS_DP<7>")
		)
		(pad "273" smd rect
			(at 2.050034 50.574956 270)
			(size 0.519938 1.4986)
			(layers "F.Cu" "F.Mask" "F.Paste")
			(net "GND")
		)
		(pad "274" smd rect
			(at 2.050034 51.425094 270)
			(size 0.519938 1.4986)
			(layers "F.Cu" "F.Mask" "F.Paste")
			(net "M_F_CPU0_SB_DQ<22>")
		)
		(pad "275" smd rect
			(at 2.050034 52.274978 270)
			(size 0.519938 1.4986)
			(layers "F.Cu" "F.Mask" "F.Paste")
			(net "GND")
		)
		(pad "276" smd rect
			(at 2.050034 53.125116 270)
			(size 0.519938 1.4986)
			(layers "F.Cu" "F.Mask" "F.Paste")
			(net "M_F_CPU0_SB_DQ<23>")
		)
		(pad "277" smd rect
			(at 2.050034 53.975 270)
			(size 0.519938 1.4986)
			(layers "F.Cu" "F.Mask" "F.Paste")
			(net "GND")
		)
		(pad "278" smd rect
			(at 2.050034 54.824884 270)
			(size 0.519938 1.4986)
			(layers "F.Cu" "F.Mask" "F.Paste")
			(net "M_F_CPU0_SB_DQ<26>")
		)
		(pad "279" smd rect
			(at 2.050034 55.675022 270)
			(size 0.519938 1.4986)
			(layers "F.Cu" "F.Mask" "F.Paste")
			(net "GND")
		)
		(pad "280" smd rect
			(at 2.050034 56.524906 270)
			(size 0.519938 1.4986)
			(layers "F.Cu" "F.Mask" "F.Paste")
			(net "M_F_CPU0_SB_DQ<27>")
		)
		(pad "281" smd rect
			(at 2.050034 57.375044 270)
			(size 0.519938 1.4986)
			(layers "F.Cu" "F.Mask" "F.Paste")
			(net "GND")
		)
		(pad "282" smd rect
			(at 2.050034 58.224928 270)
			(size 0.519938 1.4986)
			(layers "F.Cu" "F.Mask" "F.Paste")
			(net "M_F_CPU0_SB_DQS_DN<8>")
		)
		(pad "283" smd rect
			(at 2.050034 59.075066 270)
			(size 0.519938 1.4986)
			(layers "F.Cu" "F.Mask" "F.Paste")
			(net "M_F_CPU0_SB_DQS_DP<8>")
		)
		(pad "284" smd rect
			(at 2.050034 59.92495 270)
			(size 0.519938 1.4986)
			(layers "F.Cu" "F.Mask" "F.Paste")
			(net "GND")
		)
		(pad "285" smd rect
			(at 2.050034 60.775088 270)
			(size 0.519938 1.4986)
			(layers "F.Cu" "F.Mask" "F.Paste")
			(net "M_F_CPU0_SB_DQ<30>")
		)
		(pad "286" smd rect
			(at 2.050034 61.624972 270)
			(size 0.519938 1.4986)
			(layers "F.Cu" "F.Mask" "F.Paste")
			(net "GND")
		)
		(pad "287" smd rect
			(at 2.050034 62.47511 270)
			(size 0.519938 1.4986)
			(layers "F.Cu" "F.Mask" "F.Paste")
			(net "M_F_CPU0_SB_DQ<31>")
		)
		(pad "288" smd rect
			(at 2.050034 63.324994 270)
			(size 0.519938 1.4986)
			(layers "F.Cu" "F.Mask" "F.Paste")
			(net "GND")
		)
		(pad "G1" thru_hole oval
			(at 0 -68.97497)
			(size 2.8194 1.5748)
			(drill oval 2.4384 1.1938)
			(layers "*.Cu" "*.Mask")
			(remove_unused_layers no)
			(net "GND")
			(clearance 0.127)
			(thermal_gap 0.127)
		)
		(pad "G2" thru_hole oval
			(at 0 3.875024)
			(size 2.8194 1.5748)
			(drill oval 2.4384 1.1938)
			(layers "*.Cu" "*.Mask")
			(remove_unused_layers no)
			(net "GND")
			(clearance 0.127)
			(thermal_gap 0.127)
		)
		(pad "G3" thru_hole oval
			(at 0 68.97497)
			(size 2.8194 1.5748)
			(drill oval 2.4384 1.1938)
			(layers "*.Cu" "*.Mask")
			(remove_unused_layers no)
			(net "GND")
			(clearance 0.127)
			(thermal_gap 0.127)
		)
	)
)
